# S9S_MB_2U (Grand Teton) — schematic netlist excerpt (pin names and nets, part order shuffled) for the footprints in the layout excerpt that follows; sources: Cadence DE-HDL packaged netlist, KiCad conversion of 03242023_DA0F0TMBIJ0_F0T_Motherboard_J_brd_V01_OCP.brd

J7  SCONN288_ADR50017P130CC  SCONN288_ADR50017-P130CC IO  pkg DDR288S_1-1VXB  page 88
  VIN_BULK0  = P12V_S3_AUX_CPU0_NVDIMM
  RFU0  = TP_CHD_CPU0_DIMM1_FRU_0
  VIN_MGMT  = P3V3_AUX
  HSCL  = I3C_SPD_DDRABCD_CPU0_LVC1_SCL_6
  HSDA  = I3C_SPD_DDRABCD_CPU0_LVC1_SDA
  VSS0  = GND
  DQ0_A  = M_D_CPU0_SA_DQ<0>
  VSS1  = GND
  DQ1_A  = M_D_CPU0_SA_DQ<1>
  VSS2  = GND
  DQS0_A_T  = M_D_CPU0_SA_DQS_DP<0>
  DQS0_A_C  = M_D_CPU0_SA_DQS_DN<0>
  VSS3  = GND
  DQ4_A  = M_D_CPU0_SA_DQ<4>
  VSS4  = GND
  DQ5_A  = M_D_CPU0_SA_DQ<5>
  VSS5  = GND
  DQ8_A  = M_D_CPU0_SA_DQ<8>
  VSS6  = GND
  DQ9_A  = M_D_CPU0_SA_DQ<9>
  VSS7  = GND
  DQS1_A_T  = M_D_CPU0_SA_DQS_DP<1>
  DQS1_A_C  = M_D_CPU0_SA_DQS_DN<1>
  VSS8  = GND
  DQ12_A  = M_D_CPU0_SA_DQ<12>
  VSS9  = GND
  DQ13_A  = M_D_CPU0_SA_DQ<13>
  VSS10  = GND
  DQ16_A  = M_D_CPU0_SA_DQ<16>
  VSS11  = GND
  DQ17_A  = M_D_CPU0_SA_DQ<17>
  VSS12  = GND
  DQS2_A_T  = M_D_CPU0_SA_DQS_DP<2>
  DQS2_A_C  = M_D_CPU0_SA_DQS_DN<2>
  VSS13  = GND
  DQ20_A  = M_D_CPU0_SA_DQ<20>
  VSS14  = GND
  DQ21_A  = M_D_CPU0_SA_DQ<21>
  VSS15  = GND
  DQ24_A  = M_D_CPU0_SA_DQ<24>
  VSS16  = GND
  DQ25_A  = M_D_CPU0_SA_DQ<25>
  VSS17  = GND
  DQS3_A_T  = M_D_CPU0_SA_DQS_DP<3>
  DQS3_A_C  = M_D_CPU0_SA_DQS_DN<3>
  VSS18  = GND
  DQ28_A  = M_D_CPU0_SA_DQ<28>
  VSS19  = GND
  DQ29_A  = M_D_CPU0_SA_DQ<29>
  VSS20  = GND
  CB0_A  = M_D_CPU0_SA_CB<0>
  VSS21  = GND
  CB1_A  = M_D_CPU0_SA_CB<1>
  VSS22  = GND
  DQS4_A_T  = M_D_CPU0_SA_DQS_DP<4>
  DQS4_A_C  = M_D_CPU0_SA_DQS_DN<4>
  VSS23  = GND
  CB4_A  = M_D_CPU0_SA_CB<4>
  VSS24  = GND
  CB5_A  = M_D_CPU0_SA_CB<5>
  VSS25  = GND
  ALERT_N  = M_D_CPU0_ALERT_N
  VSS26  = GND
  CS0_A_N  = M_D_CPU0_SA_CS_N<0>
  VSS27  = GND
  CA0_A  = M_D_CPU0_SA_CA<0>
  VSS28  = GND
  CA2_A  = M_D_CPU0_SA_CA<2>
  VSS29  = GND
  CA4_A  = M_D_CPU0_SA_CA<4>
  VSS30  = GND
  CA6_A  = M_D_CPU0_SA_CA<6>
  VSS31  = GND
  PAR_A  = M_D_CPU0_SA_PAR
  VSS32  = GND
  CA0_B  = M_D_CPU0_SB_CA<0>
  VSS33  = GND
  CA2_B  = M_D_CPU0_SB_CA<2>
  VSS34  = GND
  CA4_B  = M_D_CPU0_SB_CA<4>
  VSS35  = GND
  CA6_B  = M_D_CPU0_SB_CA<6>
  VSS36  = GND
  CS0_B_N  = M_D_CPU0_SB_CS_N<0>
  VSS37  = GND
  \lbd||rsp_a_n\  = M_D_CPU0_SA_RSP<0>
  \lbs||rsp_b_n\  = M_D_CPU0_SB_RSP<0>
  VSS38  = GND
  CB4_B  = M_D_CPU0_SB_CB<4>
  VSS39  = GND
  CB5_B  = M_D_CPU0_SB_CB<5>
  VSS40  = GND
  \dqs9_b_t||tdqs9_b_t||dbi4_b_n\  = M_D_CPU0_SB_DQS_DP<9>
  \dqs9_b_c||tdqs9_b_c\  = M_D_CPU0_SB_DQS_DN<9>
  VSS41  = GND
  CB0_B  = M_D_CPU0_SB_CB<0>
  VSS42  = GND
  CB1_B  = M_D_CPU0_SB_CB<1>
  VSS43  = GND
  DQ0_B  = M_D_CPU0_SB_DQ<0>
  VSS44  = GND
  DQ1_B  = M_D_CPU0_SB_DQ<1>
  VSS45  = GND
  DQS0_B_T  = M_D_CPU0_SB_DQS_DP<0>
  DQS0_B_C  = M_D_CPU0_SB_DQS_DN<0>
  VSS46  = GND
  DQ4_B  = M_D_CPU0_SB_DQ<4>
  VSS47  = GND
  DQ5_B  = M_D_CPU0_SB_DQ<5>
  VSS48  = GND
  DQ8_B  = M_D_CPU0_SB_DQ<8>
  VSS49  = GND
  DQ9_B  = M_D_CPU0_SB_DQ<9>
  VSS50  = GND
  DQS1_B_T  = M_D_CPU0_SB_DQS_DP<1>
  DQS1_B_C  = M_D_CPU0_SB_DQS_DN<1>
  VSS51  = GND
  DQ12_B  = M_D_CPU0_SB_DQ<12>
  VSS52  = GND
  DQ13_B  = M_D_CPU0_SB_DQ<13>
  VSS53  = GND
  DQ16_B  = M_D_CPU0_SB_DQ<16>
  VSS54  = GND
  DQ17_B  = M_D_CPU0_SB_DQ<17>
  VSS55  = GND
  DQS2_B_T  = M_D_CPU0_SB_DQS_DP<2>
  DQS2_B_C  = M_D_CPU0_SB_DQS_DN<2>
  VSS56  = GND
  DQ20_B  = M_D_CPU0_SB_DQ<20>
  VSS57  = GND
  DQ21_B  = M_D_CPU0_SB_DQ<21>
  VSS58  = GND
  DQ24_B  = M_D_CPU0_SB_DQ<24>
  VSS59  = GND
  DQ25_B  = M_D_CPU0_SB_DQ<25>
  VSS60  = GND
  DQS3_B_T  = M_D_CPU0_SB_DQS_DP<3>
  DQS3_B_C  = M_D_CPU0_SB_DQS_DN<3>
  VSS61  = GND
  DQ28_B  = M_D_CPU0_SB_DQ<28>
  VSS62  = GND
  DQ29_B  = M_D_CPU0_SB_DQ<29>
  VSS63  = GND
  RFU1  = TP_CHD_CPU0_DIMM1_FRU_1
  VIN_BULK1  = P12V_S3_AUX_CPU0_NVDIMM
  VIN_BULK2  = P12V_S3_AUX_CPU0_NVDIMM
  \pwr_good||fail_n\  = PWRGD_CHD_CPU0_DIMM1
  HSA  = PD_CHD_CPU0_DIMM1_SAA
  RFU2  = TP_CHD_CPU0_DIMM1_FRU_2
  RFU3  = TP_CHD_CPU0_DIMM1_FRU_3
  VSS64  = GND
  DQ2_A  = M_D_CPU0_SA_DQ<2>
  VSS65  = GND
  DQ3_A  = M_D_CPU0_SA_DQ<3>
  VSS66  = GND
  \dqs5_a_c||tdqs5_a_c||dqs5_a_t||tdqs5_a_t\  = M_D_CPU0_SA_DQS_DN<5>
  \dqs5_a_t||tdqs5_a_t\  = M_D_CPU0_SA_DQS_DP<5>
  VSS67  = GND
  DQ6_A  = M_D_CPU0_SA_DQ<6>
  VSS68  = GND
  DQ7_A  = M_D_CPU0_SA_DQ<7>
  VSS69  = GND
  DQ10_A  = M_D_CPU0_SA_DQ<10>
  VSS70  = GND
  DQ11_A  = M_D_CPU0_SA_DQ<11>
  VSS71  = GND
  \dqs6_a_c||tdqs6_a_c||dqs6_a_t||tdqs6_a_t\  = M_D_CPU0_SA_DQS_DN<6>
  \dqs6_a_t||tdqs6_a_t\  = M_D_CPU0_SA_DQS_DP<6>
  VSS72  = GND
  DQ14_A  = M_D_CPU0_SA_DQ<14>
  VSS73  = GND
  DQ15_A  = M_D_CPU0_SA_DQ<15>
  VSS74  = GND
  DQ18_A  = M_D_CPU0_SA_DQ<18>
  VSS75  = GND
  DQ19_A  = M_D_CPU0_SA_DQ<19>
  VSS76  = GND
  \dqs7_a_c||tdqs7_a_c\  = M_D_CPU0_SA_DQS_DN<7>
  \dqs7_a_t||tdqs7_a_t\  = M_D_CPU0_SA_DQS_DP<7>
  VSS77  = GND
  DQ22_A  = M_D_CPU0_SA_DQ<22>
  VSS78  = GND
  DQ23_A  = M_D_CPU0_SA_DQ<23>
  VSS79  = GND
  DQ26_A  = M_D_CPU0_SA_DQ<26>
  VSS80  = GND
  DQ27_A  = M_D_CPU0_SA_DQ<27>
  VSS81  = GND
  \dqs8_a_c||tdqs8_a_c\  = M_D_CPU0_SA_DQS_DN<8>
  \dqs8_a_t||tdqs8_a_t\  = M_D_CPU0_SA_DQS_DP<8>
  VSS82  = GND
  DQ30_A  = M_D_CPU0_SA_DQ<30>
  VSS83  = GND
  DQ31_A  = M_D_CPU0_SA_DQ<31>
  VSS84  = GND
  CB2_A  = M_D_CPU0_SA_CB<2>
  VSS85  = GND
  CB3_A  = M_D_CPU0_SA_CB<3>
  VSS86  = GND
  \dqs9_a_c||tdqs9_a_c\  = M_D_CPU0_SA_DQS_DN<9>
  \dqs9_a_t||tdqs9_a_t\  = M_D_CPU0_SA_DQS_DP<9>
  VSS87  = GND
  CB6_A  = M_D_CPU0_SA_CB<6>
  VSS88  = GND
  CB7_A  = M_D_CPU0_SA_CB<7>
  VSS89  = GND
  RESET_N  = RST_M_CD_CPU0_FPGA_N
  VSS90  = GND
  CS1_A_N  = M_D_CPU0_SA_CS_N<1>
  VSS91  = GND
  CA1_A  = M_D_CPU0_SA_CA<1>
  VSS92  = GND
  CA3_A  = M_D_CPU0_SA_CA<3>
  VSS93  = GND
  CA5_A  = M_D_CPU0_SA_CA<5>
  VSS94  = GND
  CK_T  = M_D_CPU0_CLK_DP<0>
  CK_C  = M_D_CPU0_CLK_DN<0>
  VSS95  = GND
  RFU4  = TP_CHD_CPU0_DIMM1_FRU_4
  CA1_B  = M_D_CPU0_SB_CA<1>
  VSS96  = GND
  CA3_B  = M_D_CPU0_SB_CA<3>
  VSS97  = GND
  CA5_B  = M_D_CPU0_SB_CA<5>
  VSS98  = GND
  PAR_B  = M_D_CPU0_SB_PAR
  VSS99  = GND
  CS1_B_N  = M_D_CPU0_SB_CS_N<1>
  VSS100  = GND
  RFU5  = TP_CHD_CPU0_DIMM1_FRU_5
  RFU6  = TP_CHD_CPU0_DIMM1_FRU_6
  VSS101  = GND
  CB6_B  = M_D_CPU0_SB_CB<6>
  VSS102  = GND
  CB7_B  = M_D_CPU0_SB_CB<7>
  VSS103  = GND
  DQS4_B_C  = M_D_CPU0_SB_DQS_DN<4>
  DQS4_B_T  = M_D_CPU0_SB_DQS_DP<4>
  VSS104  = GND
  CB2_B  = M_D_CPU0_SB_CB<2>
  VSS105  = GND
  CB3_B  = M_D_CPU0_SB_CB<3>
  VSS106  = GND
  DQ2_B  = M_D_CPU0_SB_DQ<2>
  VSS107  = GND
  DQ3_B  = M_D_CPU0_SB_DQ<3>
  VSS108  = GND
  \dqs5_b_c||tdqs5_b_c\  = M_D_CPU0_SB_DQS_DN<5>
  \dqs5_b_t||tdqs5_b_t\  = M_D_CPU0_SB_DQS_DP<5>
  VSS109  = GND
  DQ6_B  = M_D_CPU0_SB_DQ<6>
  VSS110  = GND
  DQ7_B  = M_D_CPU0_SB_DQ<7>
  VSS111  = GND
  DQ10_B  = M_D_CPU0_SB_DQ<10>
  VSS112  = GND
  DQ11_B  = M_D_CPU0_SB_DQ<11>
  VSS113  = GND
  \dqs6_b_c||tdqs6_b_c\  = M_D_CPU0_SB_DQS_DN<6>
  \dqs6_b_t||tdqs6_b_t\  = M_D_CPU0_SB_DQS_DP<6>
  VSS114  = GND
  DQ14_B  = M_D_CPU0_SB_DQ<14>
  VSS115  = GND
  DQ15_B  = M_D_CPU0_SB_DQ<15>
  VSS116  = GND
  DQ18_B  = M_D_CPU0_SB_DQ<18>
  VSS117  = GND
  DQ19_B  = M_D_CPU0_SB_DQ<19>
  VSS118  = GND
  \dqs7_b_c||tdqs7_b_c\  = M_D_CPU0_SB_DQS_DN<7>
  \dqs7_b_t||tdqs7_b_t\  = M_D_CPU0_SB_DQS_DP<7>
  VSS119  = GND
  DQ22_B  = M_D_CPU0_SB_DQ<22>
  VSS120  = GND
  DQ23_B  = M_D_CPU0_SB_DQ<23>
  VSS121  = GND
  DQ26_B  = M_D_CPU0_SB_DQ<26>
  VSS122  = GND
  DQ27_B  = M_D_CPU0_SB_DQ<27>
  VSS123  = GND
  \dqs8_b_c||tdqs8_b_c\  = M_D_CPU0_SB_DQS_DN<8>
  \dqs8_b_t||tdqs8_b_t\  = M_D_CPU0_SB_DQS_DP<8>
  VSS124  = GND
  DQ30_B  = M_D_CPU0_SB_DQ<30>
  VSS125  = GND
  DQ31_B  = M_D_CPU0_SB_DQ<31>
  VSS126  = GND
  G1  = GND
  G2  = GND
  G3  = GND

(kicad_pcb
	(version 20260206)
	(generator "pcbnew")
	(generator_version "10.0")
	(general
		(thickness 1.6)
		(legacy_teardrops no)
	)
	(paper "A4")
	(title_block
		(title "03242023_DA0F0TMBIJ0_F0T_Motherboard_J_brd_V01_OCP.brd")
		(comment 1 "Grand Teton / footprint 37 of 6105 (J7), pads 92-137 of 291")
	)
	(layers
		(0 "F.Cu" signal "TOP")
		(4 "In1.Cu" signal "GND")
		(6 "In2.Cu" signal "IN1")
		(8 "In3.Cu" signal "GND1")
		(10 "In4.Cu" signal "IN2")
		(12 "In5.Cu" signal "GND2")
		(14 "In6.Cu" signal "IN3")
		(16 "In7.Cu" signal "GND3")
		(18 "In8.Cu" signal "VCC")
		(20 "In9.Cu" signal "VCC1")
		(22 "In10.Cu" signal "GND4")
		(24 "In11.Cu" signal "IN4")
		(26 "In12.Cu" signal "GND5")
		(28 "In13.Cu" signal "IN5")
		(30 "In14.Cu" signal "GND6")
		(32 "In15.Cu" signal "IN6")
		(34 "In16.Cu" signal "GND7")
		(2 "B.Cu" signal "BOTTOM")
		(9 "F.Adhes" user "F.Adhesive")
		(11 "B.Adhes" user "B.Adhesive")
		(13 "F.Paste" user "Package Geometry/Pastemask Top")
		(15 "B.Paste" user "Package Geometry/Pastemask Bottom")
		(5 "F.SilkS" user "Ref Des/Silkscreen Top")
		(7 "B.SilkS" user "Ref Des/Silkscreen Bottom")
		(1 "F.Mask" user "Board Geometry/Soldermask Top")
		(3 "B.Mask" user "Board Geometry/Soldermask Bottom")
		(17 "Dwgs.User" user "User.Drawings")
		(19 "Cmts.User" user "User.Comments")
		(21 "Eco1.User" user "User.Eco1")
		(23 "Eco2.User" user "User.Eco2")
		(25 "Edge.Cuts" user "Board Geometry/Outline")
		(27 "Margin" user)
		(31 "F.CrtYd" user "Package Geometry/Place Bound Top")
		(29 "B.CrtYd" user "Package Geometry/Place Bound Bottom")
		(35 "F.Fab" user "Ref Des/Assembly Top")
		(33 "B.Fab" user "Ref Des/Assembly Bottom")
	)
	(footprint ""
		(layer "F.Cu")
		(at 258.130548 -258.091686)
		(property "Reference" "J7"
			(at -3.683 -81.702148 0)
			(unlocked yes)
			(layer "F.SilkS")
			(effects
				(font
					(size 0.7874 0.5842)
					(thickness 0.1524)
				)
				(justify left)
			)
		)
		(property "Value" ""
			(at 0 0 0)
			(layer "F.Fab")
			(effects
				(font
					(size 1.27 1.27)
				)
			)
		)
		(duplicate_pad_numbers_are_jumpers no)
		(pad "92" smd rect
			(at -2.050034 19.12493 270)
			(size 0.519938 1.4986)
			(layers "F.Cu" "F.Mask" "F.Paste")
			(net "GND")
		)
		(pad "93" smd rect
			(at -2.050034 19.975068 270)
			(size 0.519938 1.4986)
			(layers "F.Cu" "F.Mask" "F.Paste")
			(net "M_D_CPU0_SB_DQS_DP<9>")
		)
		(pad "94" smd rect
			(at -2.050034 20.824952 270)
			(size 0.519938 1.4986)
			(layers "F.Cu" "F.Mask" "F.Paste")
			(net "M_D_CPU0_SB_DQS_DN<9>")
		)
		(pad "95" smd rect
			(at -2.050034 21.67509 270)
			(size 0.519938 1.4986)
			(layers "F.Cu" "F.Mask" "F.Paste")
			(net "GND")
		)
		(pad "96" smd rect
			(at -2.050034 22.524974 270)
			(size 0.519938 1.4986)
			(layers "F.Cu" "F.Mask" "F.Paste")
			(net "M_D_CPU0_SB_CB<0>")
		)
		(pad "97" smd rect
			(at -2.050034 23.375112 270)
			(size 0.519938 1.4986)
			(layers "F.Cu" "F.Mask" "F.Paste")
			(net "GND")
		)
		(pad "98" smd rect
			(at -2.050034 24.224996 270)
			(size 0.519938 1.4986)
			(layers "F.Cu" "F.Mask" "F.Paste")
			(net "M_D_CPU0_SB_CB<1>")
		)
		(pad "99" smd rect
			(at -2.050034 25.07488 270)
			(size 0.519938 1.4986)
			(layers "F.Cu" "F.Mask" "F.Paste")
			(net "GND")
		)
		(pad "100" smd rect
			(at -2.050034 25.925018 270)
			(size 0.519938 1.4986)
			(layers "F.Cu" "F.Mask" "F.Paste")
			(net "M_D_CPU0_SB_DQ<0>")
		)
		(pad "101" smd rect
			(at -2.050034 26.774902 270)
			(size 0.519938 1.4986)
			(layers "F.Cu" "F.Mask" "F.Paste")
			(net "GND")
		)
		(pad "102" smd rect
			(at -2.050034 27.62504 270)
			(size 0.519938 1.4986)
			(layers "F.Cu" "F.Mask" "F.Paste")
			(net "M_D_CPU0_SB_DQ<1>")
		)
		(pad "103" smd rect
			(at -2.050034 28.474924 270)
			(size 0.519938 1.4986)
			(layers "F.Cu" "F.Mask" "F.Paste")
			(net "GND")
		)
		(pad "104" smd rect
			(at -2.050034 29.325062 270)
			(size 0.519938 1.4986)
			(layers "F.Cu" "F.Mask" "F.Paste")
			(net "M_D_CPU0_SB_DQS_DP<0>")
		)
		(pad "105" smd rect
			(at -2.050034 30.174946 270)
			(size 0.519938 1.4986)
			(layers "F.Cu" "F.Mask" "F.Paste")
			(net "M_D_CPU0_SB_DQS_DN<0>")
		)
		(pad "106" smd rect
			(at -2.050034 31.025084 270)
			(size 0.519938 1.4986)
			(layers "F.Cu" "F.Mask" "F.Paste")
			(net "GND")
		)
		(pad "107" smd rect
			(at -2.050034 31.874968 270)
			(size 0.519938 1.4986)
			(layers "F.Cu" "F.Mask" "F.Paste")
			(net "M_D_CPU0_SB_DQ<4>")
		)
		(pad "108" smd rect
			(at -2.050034 32.725106 270)
			(size 0.519938 1.4986)
			(layers "F.Cu" "F.Mask" "F.Paste")
			(net "GND")
		)
		(pad "109" smd rect
			(at -2.050034 33.57499 270)
			(size 0.519938 1.4986)
			(layers "F.Cu" "F.Mask" "F.Paste")
			(net "M_D_CPU0_SB_DQ<5>")
		)
		(pad "110" smd rect
			(at -2.050034 34.425128 270)
			(size 0.519938 1.4986)
			(layers "F.Cu" "F.Mask" "F.Paste")
			(net "GND")
		)
		(pad "111" smd rect
			(at -2.050034 35.275012 270)
			(size 0.519938 1.4986)
			(layers "F.Cu" "F.Mask" "F.Paste")
			(net "M_D_CPU0_SB_DQ<8>")
		)
		(pad "112" smd rect
			(at -2.050034 36.124896 270)
			(size 0.519938 1.4986)
			(layers "F.Cu" "F.Mask" "F.Paste")
			(net "GND")
		)
		(pad "113" smd rect
			(at -2.050034 36.975034 270)
			(size 0.519938 1.4986)
			(layers "F.Cu" "F.Mask" "F.Paste")
			(net "M_D_CPU0_SB_DQ<9>")
		)
		(pad "114" smd rect
			(at -2.050034 37.824918 270)
			(size 0.519938 1.4986)
			(layers "F.Cu" "F.Mask" "F.Paste")
			(net "GND")
		)
		(pad "115" smd rect
			(at -2.050034 38.675056 270)
			(size 0.519938 1.4986)
			(layers "F.Cu" "F.Mask" "F.Paste")
			(net "M_D_CPU0_SB_DQS_DP<1>")
		)
		(pad "116" smd rect
			(at -2.050034 39.52494 270)
			(size 0.519938 1.4986)
			(layers "F.Cu" "F.Mask" "F.Paste")
			(net "M_D_CPU0_SB_DQS_DN<1>")
		)
		(pad "117" smd rect
			(at -2.050034 40.375078 270)
			(size 0.519938 1.4986)
			(layers "F.Cu" "F.Mask" "F.Paste")
			(net "GND")
		)
		(pad "118" smd rect
			(at -2.050034 41.224962 270)
			(size 0.519938 1.4986)
			(layers "F.Cu" "F.Mask" "F.Paste")
			(net "M_D_CPU0_SB_DQ<12>")
		)
		(pad "119" smd rect
			(at -2.050034 42.0751 270)
			(size 0.519938 1.4986)
			(layers "F.Cu" "F.Mask" "F.Paste")
			(net "GND")
		)
		(pad "120" smd rect
			(at -2.050034 42.924984 270)
			(size 0.519938 1.4986)
			(layers "F.Cu" "F.Mask" "F.Paste")
			(net "M_D_CPU0_SB_DQ<13>")
		)
		(pad "121" smd rect
			(at -2.050034 43.775122 270)
			(size 0.519938 1.4986)
			(layers "F.Cu" "F.Mask" "F.Paste")
			(net "GND")
		)
		(pad "122" smd rect
			(at -2.050034 44.625006 270)
			(size 0.519938 1.4986)
			(layers "F.Cu" "F.Mask" "F.Paste")
			(net "M_D_CPU0_SB_DQ<16>")
		)
		(pad "123" smd rect
			(at -2.050034 45.47489 270)
			(size 0.519938 1.4986)
			(layers "F.Cu" "F.Mask" "F.Paste")
			(net "GND")
		)
		(pad "124" smd rect
			(at -2.050034 46.325028 270)
			(size 0.519938 1.4986)
			(layers "F.Cu" "F.Mask" "F.Paste")
			(net "M_D_CPU0_SB_DQ<17>")
		)
		(pad "125" smd rect
			(at -2.050034 47.174912 270)
			(size 0.519938 1.4986)
			(layers "F.Cu" "F.Mask" "F.Paste")
			(net "GND")
		)
		(pad "126" smd rect
			(at -2.050034 48.02505 270)
			(size 0.519938 1.4986)
			(layers "F.Cu" "F.Mask" "F.Paste")
			(net "M_D_CPU0_SB_DQS_DP<2>")
		)
		(pad "127" smd rect
			(at -2.050034 48.874934 270)
			(size 0.519938 1.4986)
			(layers "F.Cu" "F.Mask" "F.Paste")
			(net "M_D_CPU0_SB_DQS_DN<2>")
		)
		(pad "128" smd rect
			(at -2.050034 49.725072 270)
			(size 0.519938 1.4986)
			(layers "F.Cu" "F.Mask" "F.Paste")
			(net "GND")
		)
		(pad "129" smd rect
			(at -2.050034 50.574956 270)
			(size 0.519938 1.4986)
			(layers "F.Cu" "F.Mask" "F.Paste")
			(net "M_D_CPU0_SB_DQ<20>")
		)
		(pad "130" smd rect
			(at -2.050034 51.425094 270)
			(size 0.519938 1.4986)
			(layers "F.Cu" "F.Mask" "F.Paste")
			(net "GND")
		)
		(pad "131" smd rect
			(at -2.050034 52.274978 270)
			(size 0.519938 1.4986)
			(layers "F.Cu" "F.Mask" "F.Paste")
			(net "M_D_CPU0_SB_DQ<21>")
		)
		(pad "132" smd rect
			(at -2.050034 53.125116 270)
			(size 0.519938 1.4986)
			(layers "F.Cu" "F.Mask" "F.Paste")
			(net "GND")
		)
		(pad "133" smd rect
			(at -2.050034 53.975 270)
			(size 0.519938 1.4986)
			(layers "F.Cu" "F.Mask" "F.Paste")
			(net "M_D_CPU0_SB_DQ<24>")
		)
		(pad "134" smd rect
			(at -2.050034 54.824884 270)
			(size 0.519938 1.4986)
			(layers "F.Cu" "F.Mask" "F.Paste")
			(net "GND")
		)
		(pad "135" smd rect
			(at -2.050034 55.675022 270)
			(size 0.519938 1.4986)
			(layers "F.Cu" "F.Mask" "F.Paste")
			(net "M_D_CPU0_SB_DQ<25>")
		)
		(pad "136" smd rect
			(at -2.050034 56.524906 270)
			(size 0.519938 1.4986)
			(layers "F.Cu" "F.Mask" "F.Paste")
			(net "GND")
		)
		(pad "137" smd rect
			(at -2.050034 57.375044 270)
			(size 0.519938 1.4986)
			(layers "F.Cu" "F.Mask" "F.Paste")
			(net "M_D_CPU0_SB_DQS_DP<3>")
		)
	)
)
